# T6G (Grand Teton) — schematic netlist excerpt (pin names and nets, part order shuffled) for the footprints in the layout excerpt that follows; sources: Cadence DE-HDL packaged netlist, KiCad conversion of 04192023_DAF0TMB3IC0_F0TG_MB_C_brd_V02_OCP.brd

R1510  Q_RES  4.7K 5% EMPTY  pkg 0201LF  page 353 : A = P1V8_CPU1_RT_1D ; B = JTAG_TDI_RT_CPU1_P3
PC130_6  Q_CAP  22UF 16V 20% X6S  pkg C0805  page 213 : A = SW_P12V_AUX_PVDDCR_CPU0_P1_FLT ; B = GND
R2670  Q_RES  4.7K 5% EMPTY  pkg 0402LF  page 248 : A = P3V3_AUX ; B = I3C_BMC_SWB_BUF_R_SCL

(kicad_pcb
	(version 20260206)
	(generator "pcbnew")
	(generator_version "10.0")
	(general
		(thickness 1.6)
		(legacy_teardrops no)
	)
	(paper "A4")
	(title_block
		(title "04192023_DAF0TMB3IC0_F0TG_MB_C_brd_V02_OCP.brd")
		(comment 1 "Grand Teton / footprints 7411-7413 of 8354")
	)
	(layers
		(0 "F.Cu" signal "TOP")
		(4 "In1.Cu" signal "GND")
		(6 "In2.Cu" signal "IN1")
		(8 "In3.Cu" signal "GND1")
		(10 "In4.Cu" signal "IN2")
		(12 "In5.Cu" signal "GND2")
		(14 "In6.Cu" signal "IN3")
		(16 "In7.Cu" signal "GND3")
		(18 "In8.Cu" signal "VCC")
		(20 "In9.Cu" signal "VCC1")
		(22 "In10.Cu" signal "GND4")
		(24 "In11.Cu" signal "IN4")
		(26 "In12.Cu" signal "GND5")
		(28 "In13.Cu" signal "IN5")
		(30 "In14.Cu" signal "GND6")
		(32 "In15.Cu" signal "IN6")
		(34 "In16.Cu" signal "GND7")
		(2 "B.Cu" signal "BOTTOM")
		(9 "F.Adhes" user "F.Adhesive")
		(11 "B.Adhes" user "B.Adhesive")
		(13 "F.Paste" user "Package Geometry/Pastemask Top")
		(15 "B.Paste" user "Package Geometry/Pastemask Bottom")
		(5 "F.SilkS" user "Ref Des/Silkscreen Top")
		(7 "B.SilkS" user "Ref Des/Silkscreen Bottom")
		(1 "F.Mask" user "Board Geometry/Soldermask Top")
		(3 "B.Mask" user "Board Geometry/Soldermask Bottom")
		(17 "Dwgs.User" user "User.Drawings")
		(19 "Cmts.User" user "User.Comments")
		(21 "Eco1.User" user "User.Eco1")
		(23 "Eco2.User" user "User.Eco2")
		(25 "Edge.Cuts" user "Board Geometry/Outline")
		(27 "Margin" user)
		(31 "F.CrtYd" user "Package Geometry/Place Bound Top")
		(29 "B.CrtYd" user "Package Geometry/Place Bound Bottom")
		(35 "F.Fab" user "Ref Des/Assembly Top")
		(33 "B.Fab" user "Ref Des/Assembly Bottom")
	)
	(footprint ""
		(layer "B.Cu")
		(at 286.004 -425.958 -90)
		(property "Reference" "R2670"
			(at 0 0 90)
			(layer "B.SilkS")
			(hide yes)
			(effects
				(font
					(size 1.27 1.27)
				)
				(justify mirror)
			)
		)
		(property "Value" ""
			(at 0 0 90)
			(layer "B.Fab")
			(effects
				(font
					(size 1.27 1.27)
				)
				(justify mirror)
			)
		)
		(duplicate_pad_numbers_are_jumpers no)
		(fp_line
			(start -0.7874 0.4064)
			(end 0.7874 0.4064)
			(stroke
				(width 0.1524)
				(type default)
			)
			(layer "B.SilkS")
		)
		(fp_line
			(start 0.7874 0.4064)
			(end 0.7874 -0.4064)
			(stroke
				(width 0.1524)
				(type default)
			)
			(layer "B.SilkS")
		)
		(fp_line
			(start -0.7874 -0.4064)
			(end -0.7874 0.4064)
			(stroke
				(width 0.1524)
				(type default)
			)
			(layer "B.SilkS")
		)
		(fp_line
			(start 0.7874 -0.4064)
			(end -0.7874 -0.4064)
			(stroke
				(width 0.1524)
				(type default)
			)
			(layer "B.SilkS")
		)
		(fp_line
			(start -0.67945 0.3048)
			(end -0.120396 0.3048)
			(stroke
				(width 0.1)
				(type default)
			)
			(layer "B.Fab")
		)
		(fp_line
			(start -0.120396 0.3048)
			(end -0.120396 0.2794)
			(stroke
				(width 0.1)
				(type default)
			)
			(layer "B.Fab")
		)
		(fp_line
			(start 0.12065 0.3048)
			(end 0.67945 0.3048)
			(stroke
				(width 0.1)
				(type default)
			)
			(layer "B.Fab")
		)
		(fp_line
			(start 0.67945 0.3048)
			(end 0.67945 -0.305054)
			(stroke
				(width 0.1)
				(type default)
			)
			(layer "B.Fab")
		)
		(fp_line
			(start -0.120396 0.2794)
			(end 0.12065 0.2794)
			(stroke
				(width 0.1)
				(type default)
			)
			(layer "B.Fab")
		)
		(fp_line
			(start 0.12065 0.2794)
			(end 0.12065 0.3048)
			(stroke
				(width 0.1)
				(type default)
			)
			(layer "B.Fab")
		)
		(fp_line
			(start -0.12065 -0.2794)
			(end -0.12065 -0.3048)
			(stroke
				(width 0.1)
				(type default)
			)
			(layer "B.Fab")
		)
		(fp_line
			(start 0.12065 -0.2794)
			(end -0.12065 -0.2794)
			(stroke
				(width 0.1)
				(type default)
			)
			(layer "B.Fab")
		)
		(fp_line
			(start -0.67945 -0.3048)
			(end -0.67945 0.3048)
			(stroke
				(width 0.1)
				(type default)
			)
			(layer "B.Fab")
		)
		(fp_line
			(start -0.12065 -0.3048)
			(end -0.67945 -0.3048)
			(stroke
				(width 0.1)
				(type default)
			)
			(layer "B.Fab")
		)
		(fp_line
			(start 0.12065 -0.305054)
			(end 0.12065 -0.2794)
			(stroke
				(width 0.1)
				(type default)
			)
			(layer "B.Fab")
		)
		(fp_line
			(start 0.67945 -0.305054)
			(end 0.12065 -0.305054)
			(stroke
				(width 0.1)
				(type default)
			)
			(layer "B.Fab")
		)
		(pad "1" smd circle
			(at 0.40005 0 90)
			(size 0 0)
			(layers "B.Cu" "B.Mask" "B.Paste")
			(net "P3V3_AUX")
		)
		(pad "2" smd circle
			(at -0.40005 0 90)
			(size 0 0)
			(layers "B.Cu" "B.Mask" "B.Paste")
			(net "I3C_BMC_SWB_BUF_R_SCL")
		)
	)
	(footprint ""
		(layer "B.Cu")
		(at 165.1508 -424.60037 -90)
		(property "Reference" "R1510"
			(at 0 0 90)
			(layer "B.SilkS")
			(hide yes)
			(effects
				(font
					(size 1.27 1.27)
				)
				(justify mirror)
			)
		)
		(property "Value" ""
			(at 0 0 90)
			(layer "B.Fab")
			(effects
				(font
					(size 1.27 1.27)
				)
				(justify mirror)
			)
		)
		(duplicate_pad_numbers_are_jumpers no)
		(fp_line
			(start -0.32512 0.175006)
			(end 0.32512 0.175006)
			(stroke
				(width 0.1)
				(type default)
			)
			(layer "B.Fab")
		)
		(fp_line
			(start 0.32512 0.175006)
			(end 0.32512 -0.175006)
			(stroke
				(width 0.1)
				(type default)
			)
			(layer "B.Fab")
		)
		(fp_line
			(start -0.32512 -0.175006)
			(end -0.32512 0.175006)
			(stroke
				(width 0.1)
				(type default)
			)
			(layer "B.Fab")
		)
		(fp_line
			(start 0.32512 -0.175006)
			(end -0.32512 -0.175006)
			(stroke
				(width 0.1)
				(type default)
			)
			(layer "B.Fab")
		)
		(pad "1" smd rect
			(at 0.2667 0 90)
			(size 0.3048 0.381)
			(layers "B.Cu" "B.Mask" "B.Paste")
			(net "P1V8_CPU1_RT_1D")
		)
		(pad "2" smd rect
			(at -0.2667 0 270)
			(size 0.3048 0.381)
			(layers "B.Cu" "B.Mask" "B.Paste")
			(net "JTAG_TDI_RT_CPU1_P3")
		)
	)
	(footprint ""
		(layer "B.Cu")
		(at 64.595248 -168.86682 -90)
		(property "Reference" "PC130_6"
			(at 0 0 90)
			(layer "B.SilkS")
			(hide yes)
			(effects
				(font
					(size 1.27 1.27)
				)
				(justify mirror)
			)
		)
		(property "Value" ""
			(at 0 0 90)
			(layer "B.Fab")
			(effects
				(font
					(size 1.27 1.27)
				)
				(justify mirror)
			)
		)
		(duplicate_pad_numbers_are_jumpers no)
		(fp_line
			(start -1.524 0.762)
			(end 1.524 0.762)
			(stroke
				(width 0.1524)
				(type default)
			)
			(layer "B.SilkS")
		)
		(fp_line
			(start 1.524 0.762)
			(end 1.524 -0.762)
			(stroke
				(width 0.1524)
				(type default)
			)
			(layer "B.SilkS")
		)
		(fp_line
			(start -1.524 -0.762)
			(end -1.524 0.762)
			(stroke
				(width 0.1524)
				(type default)
			)
			(layer "B.SilkS")
		)
		(fp_line
			(start 1.524 -0.762)
			(end -1.524 -0.762)
			(stroke
				(width 0.1524)
				(type default)
			)
			(layer "B.SilkS")
		)
		(fp_line
			(start -1.1049 0.724916)
			(end -1.1049 -0.724916)
			(stroke
				(width 0.1)
				(type default)
			)
			(layer "B.Fab")
		)
		(fp_line
			(start 1.1049 0.724916)
			(end -1.1049 0.724916)
			(stroke
				(width 0.1)
				(type default)
			)
			(layer "B.Fab")
		)
		(fp_line
			(start -1.1049 -0.724916)
			(end 1.1049 -0.724916)
			(stroke
				(width 0.1)
				(type default)
			)
			(layer "B.Fab")
		)
		(fp_line
			(start 1.1049 -0.724916)
			(end 1.1049 0.724916)
			(stroke
				(width 0.1)
				(type default)
			)
			(layer "B.Fab")
		)
		(pad "1" smd rect
			(at 0.889 0 270)
			(size 1.016 1.27)
			(layers "B.Cu" "B.Mask" "B.Paste")
			(net "SW_P12V_AUX_PVDDCR_CPU0_P1_FLT")
		)
		(pad "2" smd rect
			(at -0.889 0 270)
			(size 1.016 1.27)
			(layers "B.Cu" "B.Mask" "B.Paste")
			(net "GND")
		)
	)
)
